G04*
G04 #@! TF.GenerationSoftware,Altium Limited,Altium Designer,23.0.1 (38)*
G04*
G04 Layer_Color=16711935*
%FSLAX25Y25*%
%MOIN*%
G70*
G04*
G04 #@! TF.SameCoordinates,C48E81DB-6E20-4E2D-80E6-7C5AFAA1A21F*
G04*
G04*
G04 #@! TF.FilePolarity,Positive*
G04*
G01*
G75*
G36*
X588339Y-259298D02*
Y-284796D01*
X558905D01*
Y-259298D01*
X588339D01*
D02*
G37*
G36*
X599514Y-200692D02*
Y-226189D01*
X570079D01*
Y-200692D01*
X599514D01*
D02*
G37*
M02*
